#ISCELL
  mstr_misc dns *
  *
#ISCELL
  pure_quanta quanta_title_block_c *
  *
#ISCELL
  pure_quanta_power universal_power *
  page143_i1
#ISCELL
  pure_quanta_power universal_power *
  page143_i10
#CELL
  pure_quanta q_res *
  page143_i11
#ISCELL
  pure_quanta_power gnd *
  page143_i12
#ISCELL
  pure_quanta_power gnd *
  page143_i13
#ISCELL
  pure_quanta_power universal_power *
  page143_i14
#CELL
  pure_quanta q_res *
  page143_i15
#CELL
  pure_quanta mosfet_dual_6p *
  page143_i16
#ISCELL
  pure_quanta_power universal_power *
  page143_i17
#CELL
  pure_quanta q_res *
  page143_i18
#CELL
  pure_quanta mosfet_dual_6p *
  page143_i19
#ISCELL
  pure_quanta_power universal_power *
  page143_i2
#ISCELL
  pure_quanta_power gnd *
  page143_i20
#CELL
  pure_quanta q_res *
  page143_i21
#CELL
  pure_quanta q_res *
  page143_i22
#CELL
  pure_quanta q_cap *
  page143_i24
#ISCELL
  pure_quanta_power universal_gnd *
  page143_i25
#CELL
  pure_quanta sn74lvc1g07dbvr *
  page143_i26
#ISCELL
  pure_quanta_power universal_gnd *
  page143_i27
#ISCELL
  pure_quanta_power p1v0 *
  page143_i28
#CELL
  pure_quanta q_cap *
  page143_i29
#CELL
  pure_quanta q_res *
  page143_i3
#ISCELL
  pure_quanta_power universal_gnd *
  page143_i30
#CELL
  pure_quanta sn74lvc1g07dbvr *
  page143_i31
#ISCELL
  pure_quanta_power universal_gnd *
  page143_i32
#CELL
  pure_quanta q_res *
  page143_i33
#CELL
  pure_quanta q_res *
  page143_i34
#ISCELL
  standard offpage *
  page143_i35
#ISCELL
  standard offpage *
  page143_i36
#ISCELL
  standard offpage *
  page143_i37
#CELL
  pure_quanta q_led *
  page143_i38
#ISCELL
  pure_quanta_power universal_gnd *
  page143_i39
#ISCELL
  pure_quanta_power universal_power *
  page143_i4
#ISCELL
  pure_quanta_power p1v0 *
  page143_i40
#CELL
  pure_quanta q_res *
  page143_i41
#CELL
  pure_quanta q_res *
  page143_i42
#CELL
  pure_quanta q_led *
  page143_i43
#CELL
  pure_quanta mosfet_n_gsd *
  page143_i44
#ISCELL
  pure_quanta_power p1v0 *
  page143_i45
#ISCELL
  pure_quanta_power universal_gnd *
  page143_i46
#ISCELL
  standard offpage *
  page143_i47
#ISCELL
  pure_quanta_power p1v0 *
  page143_i48
#CELL
  pure_quanta q_res *
  page143_i5
#ISCELL
  pure_quanta_power gnd *
  page143_i6
#CELL
  pure_quanta q_res *
  page143_i7
#CELL
  pure_quanta q_led *
  page143_i8
#CELL
  pure_quanta q_led *
  page143_i9
